# T6G (Grand Teton) — schematic netlist excerpt (pin names and nets, part order shuffled) for the footprints in the layout excerpt that follows; sources: Cadence DE-HDL packaged netlist, KiCad conversion of 04192023_DAF0TMB3IC0_F0TG_MB_C_brd_V02_OCP.brd

C2295  Q_CAP  22UF 4V 20% X6S  pkg C0402  page 73 : A = PVDDCR_CPU0_P1 ; B = GND
C3896  Q_CAP  22UF 4V 20% X6S  pkg C0402  page 68 : A = PVDDCR_SOC_P0 ; B = GND

(kicad_pcb
	(version 20260206)
	(generator "pcbnew")
	(generator_version "10.0")
	(general
		(thickness 1.6)
		(legacy_teardrops no)
	)
	(paper "A4")
	(title_block
		(title "04192023_DAF0TMB3IC0_F0TG_MB_C_brd_V02_OCP.brd")
		(comment 1 "Grand Teton / footprints 6254-6255 of 8354")
	)
	(layers
		(0 "F.Cu" signal "TOP")
		(4 "In1.Cu" signal "GND")
		(6 "In2.Cu" signal "IN1")
		(8 "In3.Cu" signal "GND1")
		(10 "In4.Cu" signal "IN2")
		(12 "In5.Cu" signal "GND2")
		(14 "In6.Cu" signal "IN3")
		(16 "In7.Cu" signal "GND3")
		(18 "In8.Cu" signal "VCC")
		(20 "In9.Cu" signal "VCC1")
		(22 "In10.Cu" signal "GND4")
		(24 "In11.Cu" signal "IN4")
		(26 "In12.Cu" signal "GND5")
		(28 "In13.Cu" signal "IN5")
		(30 "In14.Cu" signal "GND6")
		(32 "In15.Cu" signal "IN6")
		(34 "In16.Cu" signal "GND7")
		(2 "B.Cu" signal "BOTTOM")
		(9 "F.Adhes" user "F.Adhesive")
		(11 "B.Adhes" user "B.Adhesive")
		(13 "F.Paste" user "Package Geometry/Pastemask Top")
		(15 "B.Paste" user "Package Geometry/Pastemask Bottom")
		(5 "F.SilkS" user "Ref Des/Silkscreen Top")
		(7 "B.SilkS" user "Ref Des/Silkscreen Bottom")
		(1 "F.Mask" user "Board Geometry/Soldermask Top")
		(3 "B.Mask" user "Board Geometry/Soldermask Bottom")
		(17 "Dwgs.User" user "User.Drawings")
		(19 "Cmts.User" user "User.Comments")
		(21 "Eco1.User" user "User.Eco1")
		(23 "Eco2.User" user "User.Eco2")
		(25 "Edge.Cuts" user "Board Geometry/Outline")
		(27 "Margin" user)
		(31 "F.CrtYd" user "Package Geometry/Place Bound Top")
		(29 "B.CrtYd" user "Package Geometry/Place Bound Bottom")
		(35 "F.Fab" user "Ref Des/Assembly Top")
		(33 "B.Fab" user "Ref Des/Assembly Bottom")
	)
	(footprint ""
		(layer "B.Cu")
		(at 99.916234 -245.868952 -90)
		(property "Reference" "C2295"
			(at 0 0 90)
			(layer "B.SilkS")
			(hide yes)
			(effects
				(font
					(size 1.27 1.27)
				)
				(justify mirror)
			)
		)
		(property "Value" ""
			(at 0 0 90)
			(layer "B.Fab")
			(effects
				(font
					(size 1.27 1.27)
				)
				(justify mirror)
			)
		)
		(duplicate_pad_numbers_are_jumpers no)
		(fp_line
			(start -0.7874 0.4064)
			(end 0.7874 0.4064)
			(stroke
				(width 0.1524)
				(type default)
			)
			(layer "B.SilkS")
		)
		(fp_line
			(start 0.7874 0.4064)
			(end 0.7874 -0.4064)
			(stroke
				(width 0.1524)
				(type default)
			)
			(layer "B.SilkS")
		)
		(fp_line
			(start -0.7874 -0.4064)
			(end -0.7874 0.4064)
			(stroke
				(width 0.1524)
				(type default)
			)
			(layer "B.SilkS")
		)
		(fp_line
			(start 0.7874 -0.4064)
			(end -0.7874 -0.4064)
			(stroke
				(width 0.1524)
				(type default)
			)
			(layer "B.SilkS")
		)
		(fp_line
			(start -0.67945 0.3048)
			(end -0.120396 0.3048)
			(stroke
				(width 0.1)
				(type default)
			)
			(layer "B.Fab")
		)
		(fp_line
			(start -0.120396 0.3048)
			(end -0.120396 0.2794)
			(stroke
				(width 0.1)
				(type default)
			)
			(layer "B.Fab")
		)
		(fp_line
			(start 0.12065 0.3048)
			(end 0.67945 0.3048)
			(stroke
				(width 0.1)
				(type default)
			)
			(layer "B.Fab")
		)
		(fp_line
			(start 0.67945 0.3048)
			(end 0.67945 -0.305054)
			(stroke
				(width 0.1)
				(type default)
			)
			(layer "B.Fab")
		)
		(fp_line
			(start -0.120396 0.2794)
			(end 0.12065 0.2794)
			(stroke
				(width 0.1)
				(type default)
			)
			(layer "B.Fab")
		)
		(fp_line
			(start 0.12065 0.2794)
			(end 0.12065 0.3048)
			(stroke
				(width 0.1)
				(type default)
			)
			(layer "B.Fab")
		)
		(fp_line
			(start -0.12065 -0.2794)
			(end -0.12065 -0.3048)
			(stroke
				(width 0.1)
				(type default)
			)
			(layer "B.Fab")
		)
		(fp_line
			(start 0.12065 -0.2794)
			(end -0.12065 -0.2794)
			(stroke
				(width 0.1)
				(type default)
			)
			(layer "B.Fab")
		)
		(fp_line
			(start -0.67945 -0.3048)
			(end -0.67945 0.3048)
			(stroke
				(width 0.1)
				(type default)
			)
			(layer "B.Fab")
		)
		(fp_line
			(start -0.12065 -0.3048)
			(end -0.67945 -0.3048)
			(stroke
				(width 0.1)
				(type default)
			)
			(layer "B.Fab")
		)
		(fp_line
			(start 0.12065 -0.305054)
			(end 0.12065 -0.2794)
			(stroke
				(width 0.1)
				(type default)
			)
			(layer "B.Fab")
		)
		(fp_line
			(start 0.67945 -0.305054)
			(end 0.12065 -0.305054)
			(stroke
				(width 0.1)
				(type default)
			)
			(layer "B.Fab")
		)
		(pad "1" smd circle
			(at 0.40005 0 90)
			(size 0 0)
			(layers "B.Cu" "B.Mask" "B.Paste")
			(net "PVDDCR_CPU0_P1")
		)
		(pad "2" smd circle
			(at -0.40005 0 90)
			(size 0 0)
			(layers "B.Cu" "B.Mask" "B.Paste")
			(net "GND")
		)
	)
	(footprint ""
		(layer "B.Cu")
		(at 367.233454 -251.78131)
		(property "Reference" "C3896"
			(at 0 0 0)
			(layer "B.SilkS")
			(hide yes)
			(effects
				(font
					(size 1.27 1.27)
				)
				(justify mirror)
			)
		)
		(property "Value" ""
			(at 0 0 0)
			(layer "B.Fab")
			(effects
				(font
					(size 1.27 1.27)
				)
				(justify mirror)
			)
		)
		(duplicate_pad_numbers_are_jumpers no)
		(fp_line
			(start -0.7874 -0.4064)
			(end -0.7874 0.4064)
			(stroke
				(width 0.1524)
				(type default)
			)
			(layer "B.SilkS")
		)
		(fp_line
			(start -0.7874 0.4064)
			(end 0.7874 0.4064)
			(stroke
				(width 0.1524)
				(type default)
			)
			(layer "B.SilkS")
		)
		(fp_line
			(start 0.7874 -0.4064)
			(end -0.7874 -0.4064)
			(stroke
				(width 0.1524)
				(type default)
			)
			(layer "B.SilkS")
		)
		(fp_line
			(start 0.7874 0.4064)
			(end 0.7874 -0.4064)
			(stroke
				(width 0.1524)
				(type default)
			)
			(layer "B.SilkS")
		)
		(fp_line
			(start -0.67945 -0.3048)
			(end -0.67945 0.3048)
			(stroke
				(width 0.1)
				(type default)
			)
			(layer "B.Fab")
		)
		(fp_line
			(start -0.67945 0.3048)
			(end -0.120396 0.3048)
			(stroke
				(width 0.1)
				(type default)
			)
			(layer "B.Fab")
		)
		(fp_line
			(start -0.12065 -0.3048)
			(end -0.67945 -0.3048)
			(stroke
				(width 0.1)
				(type default)
			)
			(layer "B.Fab")
		)
		(fp_line
			(start -0.12065 -0.2794)
			(end -0.12065 -0.3048)
			(stroke
				(width 0.1)
				(type default)
			)
			(layer "B.Fab")
		)
		(fp_line
			(start -0.120396 0.2794)
			(end 0.12065 0.2794)
			(stroke
				(width 0.1)
				(type default)
			)
			(layer "B.Fab")
		)
		(fp_line
			(start -0.120396 0.3048)
			(end -0.120396 0.2794)
			(stroke
				(width 0.1)
				(type default)
			)
			(layer "B.Fab")
		)
		(fp_line
			(start 0.12065 -0.305054)
			(end 0.12065 -0.2794)
			(stroke
				(width 0.1)
				(type default)
			)
			(layer "B.Fab")
		)
		(fp_line
			(start 0.12065 -0.2794)
			(end -0.12065 -0.2794)
			(stroke
				(width 0.1)
				(type default)
			)
			(layer "B.Fab")
		)
		(fp_line
			(start 0.12065 0.2794)
			(end 0.12065 0.3048)
			(stroke
				(width 0.1)
				(type default)
			)
			(layer "B.Fab")
		)
		(fp_line
			(start 0.12065 0.3048)
			(end 0.67945 0.3048)
			(stroke
				(width 0.1)
				(type default)
			)
			(layer "B.Fab")
		)
		(fp_line
			(start 0.67945 -0.305054)
			(end 0.12065 -0.305054)
			(stroke
				(width 0.1)
				(type default)
			)
			(layer "B.Fab")
		)
		(fp_line
			(start 0.67945 0.3048)
			(end 0.67945 -0.305054)
			(stroke
				(width 0.1)
				(type default)
			)
			(layer "B.Fab")
		)
		(pad "1" smd circle
			(at 0.40005 0 180)
			(size 0 0)
			(layers "B.Cu" "B.Mask" "B.Paste")
			(net "PVDDCR_SOC_P0")
		)
		(pad "2" smd circle
			(at -0.40005 0 180)
			(size 0 0)
			(layers "B.Cu" "B.Mask" "B.Paste")
			(net "GND")
		)
	)
)
